# T6G (Grand Teton) — schematic netlist excerpt (pin names and nets, part order shuffled) for the footprints in the layout excerpt that follows; sources: Cadence DE-HDL packaged netlist, KiCad conversion of 04192023_DAF0TMB3IC0_F0TG_MB_C_brd_V02_OCP.brd

R980  Q_RES  10K 1% CHIP  pkg 0201LF  page 276 : A = GPIO3_RT_CPU0_P0 ; B = GND
PC121  Q_CAP  0.22UF 16V 10% X7R  pkg 0402  page 202 : A = SW_PVDDCR_CPU1_P0_BOOT4_R ; B = SW_PVDDCR_CPU1_P0_BOOTR4
R6049  Q_RES  4.7K 5% CHIP  pkg 0402LF  page 146 : A = P3V3_E1S_EN_0_R ; B = GND

(kicad_pcb
	(version 20260206)
	(generator "pcbnew")
	(generator_version "10.0")
	(general
		(thickness 1.6)
		(legacy_teardrops no)
	)
	(paper "A4")
	(title_block
		(title "04192023_DAF0TMB3IC0_F0TG_MB_C_brd_V02_OCP.brd")
		(comment 1 "Grand Teton / footprints 2153-2155 of 8354")
	)
	(layers
		(0 "F.Cu" signal "TOP")
		(4 "In1.Cu" signal "GND")
		(6 "In2.Cu" signal "IN1")
		(8 "In3.Cu" signal "GND1")
		(10 "In4.Cu" signal "IN2")
		(12 "In5.Cu" signal "GND2")
		(14 "In6.Cu" signal "IN3")
		(16 "In7.Cu" signal "GND3")
		(18 "In8.Cu" signal "VCC")
		(20 "In9.Cu" signal "VCC1")
		(22 "In10.Cu" signal "GND4")
		(24 "In11.Cu" signal "IN4")
		(26 "In12.Cu" signal "GND5")
		(28 "In13.Cu" signal "IN5")
		(30 "In14.Cu" signal "GND6")
		(32 "In15.Cu" signal "IN6")
		(34 "In16.Cu" signal "GND7")
		(2 "B.Cu" signal "BOTTOM")
		(9 "F.Adhes" user "F.Adhesive")
		(11 "B.Adhes" user "B.Adhesive")
		(13 "F.Paste" user "Package Geometry/Pastemask Top")
		(15 "B.Paste" user "Package Geometry/Pastemask Bottom")
		(5 "F.SilkS" user "Ref Des/Silkscreen Top")
		(7 "B.SilkS" user "Ref Des/Silkscreen Bottom")
		(1 "F.Mask" user "Board Geometry/Soldermask Top")
		(3 "B.Mask" user "Board Geometry/Soldermask Bottom")
		(17 "Dwgs.User" user "User.Drawings")
		(19 "Cmts.User" user "User.Comments")
		(21 "Eco1.User" user "User.Eco1")
		(23 "Eco2.User" user "User.Eco2")
		(25 "Edge.Cuts" user "Board Geometry/Outline")
		(27 "Margin" user)
		(31 "F.CrtYd" user "Package Geometry/Place Bound Top")
		(29 "B.CrtYd" user "Package Geometry/Place Bound Bottom")
		(35 "F.Fab" user "Ref Des/Assembly Top")
		(33 "B.Fab" user "Ref Des/Assembly Bottom")
	)
	(footprint ""
		(layer "F.Cu")
		(at 310.48198 -351.368106 -90)
		(property "Reference" "PC121"
			(at 0 0 270)
			(layer "F.SilkS")
			(hide yes)
			(effects
				(font
					(size 1.27 1.27)
				)
			)
		)
		(property "Value" ""
			(at 0 0 270)
			(layer "F.Fab")
			(effects
				(font
					(size 1.27 1.27)
				)
			)
		)
		(duplicate_pad_numbers_are_jumpers no)
		(fp_line
			(start -0.7874 0.4064)
			(end -0.7874 -0.4064)
			(stroke
				(width 0.1524)
				(type default)
			)
			(layer "F.SilkS")
		)
		(fp_line
			(start 0.7874 0.4064)
			(end -0.7874 0.4064)
			(stroke
				(width 0.1524)
				(type default)
			)
			(layer "F.SilkS")
		)
		(fp_line
			(start -0.7874 -0.4064)
			(end 0.7874 -0.4064)
			(stroke
				(width 0.1524)
				(type default)
			)
			(layer "F.SilkS")
		)
		(fp_line
			(start 0.7874 -0.4064)
			(end 0.7874 0.4064)
			(stroke
				(width 0.1524)
				(type default)
			)
			(layer "F.SilkS")
		)
		(fp_line
			(start -0.67945 0.3048)
			(end -0.67945 -0.305054)
			(stroke
				(width 0.1)
				(type default)
			)
			(layer "F.Fab")
		)
		(fp_line
			(start -0.12065 0.3048)
			(end -0.67945 0.3048)
			(stroke
				(width 0.1)
				(type default)
			)
			(layer "F.Fab")
		)
		(fp_line
			(start 0.120396 0.3048)
			(end 0.120396 0.2794)
			(stroke
				(width 0.1)
				(type default)
			)
			(layer "F.Fab")
		)
		(fp_line
			(start 0.67945 0.3048)
			(end 0.120396 0.3048)
			(stroke
				(width 0.1)
				(type default)
			)
			(layer "F.Fab")
		)
		(fp_line
			(start -0.12065 0.2794)
			(end -0.12065 0.3048)
			(stroke
				(width 0.1)
				(type default)
			)
			(layer "F.Fab")
		)
		(fp_line
			(start 0.120396 0.2794)
			(end -0.12065 0.2794)
			(stroke
				(width 0.1)
				(type default)
			)
			(layer "F.Fab")
		)
		(fp_line
			(start -0.12065 -0.2794)
			(end 0.12065 -0.2794)
			(stroke
				(width 0.1)
				(type default)
			)
			(layer "F.Fab")
		)
		(fp_line
			(start 0.12065 -0.2794)
			(end 0.12065 -0.3048)
			(stroke
				(width 0.1)
				(type default)
			)
			(layer "F.Fab")
		)
		(fp_line
			(start 0.12065 -0.3048)
			(end 0.67945 -0.3048)
			(stroke
				(width 0.1)
				(type default)
			)
			(layer "F.Fab")
		)
		(fp_line
			(start 0.67945 -0.3048)
			(end 0.67945 0.3048)
			(stroke
				(width 0.1)
				(type default)
			)
			(layer "F.Fab")
		)
		(fp_line
			(start -0.67945 -0.305054)
			(end -0.12065 -0.305054)
			(stroke
				(width 0.1)
				(type default)
			)
			(layer "F.Fab")
		)
		(fp_line
			(start -0.12065 -0.305054)
			(end -0.12065 -0.2794)
			(stroke
				(width 0.1)
				(type default)
			)
			(layer "F.Fab")
		)
		(pad "1" smd circle
			(at -0.40005 0 270)
			(size 0 0)
			(layers "F.Cu" "F.Mask" "F.Paste")
			(net "SW_PVDDCR_CPU1_P0_BOOT4_R")
		)
		(pad "2" smd circle
			(at 0.40005 0 270)
			(size 0 0)
			(layers "F.Cu" "F.Mask" "F.Paste")
			(net "SW_PVDDCR_CPU1_P0_BOOTR4")
		)
	)
	(footprint ""
		(layer "F.Cu")
		(at 250.55957 -69.962522 180)
		(property "Reference" "R6049"
			(at 0 0 180)
			(layer "F.SilkS")
			(hide yes)
			(effects
				(font
					(size 1.27 1.27)
				)
			)
		)
		(property "Value" ""
			(at 0 0 180)
			(layer "F.Fab")
			(effects
				(font
					(size 1.27 1.27)
				)
			)
		)
		(duplicate_pad_numbers_are_jumpers no)
		(fp_line
			(start 0.7874 0.4064)
			(end -0.7874 0.4064)
			(stroke
				(width 0.1524)
				(type default)
			)
			(layer "F.SilkS")
		)
		(fp_line
			(start 0.7874 -0.4064)
			(end 0.7874 0.4064)
			(stroke
				(width 0.1524)
				(type default)
			)
			(layer "F.SilkS")
		)
		(fp_line
			(start -0.7874 0.4064)
			(end -0.7874 -0.4064)
			(stroke
				(width 0.1524)
				(type default)
			)
			(layer "F.SilkS")
		)
		(fp_line
			(start -0.7874 -0.4064)
			(end 0.7874 -0.4064)
			(stroke
				(width 0.1524)
				(type default)
			)
			(layer "F.SilkS")
		)
		(fp_line
			(start 0.67945 0.3048)
			(end 0.120396 0.3048)
			(stroke
				(width 0.1)
				(type default)
			)
			(layer "F.Fab")
		)
		(fp_line
			(start 0.67945 -0.3048)
			(end 0.67945 0.3048)
			(stroke
				(width 0.1)
				(type default)
			)
			(layer "F.Fab")
		)
		(fp_line
			(start 0.12065 -0.2794)
			(end 0.12065 -0.3048)
			(stroke
				(width 0.1)
				(type default)
			)
			(layer "F.Fab")
		)
		(fp_line
			(start 0.12065 -0.3048)
			(end 0.67945 -0.3048)
			(stroke
				(width 0.1)
				(type default)
			)
			(layer "F.Fab")
		)
		(fp_line
			(start 0.120396 0.3048)
			(end 0.120396 0.2794)
			(stroke
				(width 0.1)
				(type default)
			)
			(layer "F.Fab")
		)
		(fp_line
			(start 0.120396 0.2794)
			(end -0.12065 0.2794)
			(stroke
				(width 0.1)
				(type default)
			)
			(layer "F.Fab")
		)
		(fp_line
			(start -0.12065 0.3048)
			(end -0.67945 0.3048)
			(stroke
				(width 0.1)
				(type default)
			)
			(layer "F.Fab")
		)
		(fp_line
			(start -0.12065 0.2794)
			(end -0.12065 0.3048)
			(stroke
				(width 0.1)
				(type default)
			)
			(layer "F.Fab")
		)
		(fp_line
			(start -0.12065 -0.2794)
			(end 0.12065 -0.2794)
			(stroke
				(width 0.1)
				(type default)
			)
			(layer "F.Fab")
		)
		(fp_line
			(start -0.12065 -0.305054)
			(end -0.12065 -0.2794)
			(stroke
				(width 0.1)
				(type default)
			)
			(layer "F.Fab")
		)
		(fp_line
			(start -0.67945 0.3048)
			(end -0.67945 -0.305054)
			(stroke
				(width 0.1)
				(type default)
			)
			(layer "F.Fab")
		)
		(fp_line
			(start -0.67945 -0.305054)
			(end -0.12065 -0.305054)
			(stroke
				(width 0.1)
				(type default)
			)
			(layer "F.Fab")
		)
		(pad "1" smd circle
			(at -0.40005 0 180)
			(size 0 0)
			(layers "F.Cu" "F.Mask" "F.Paste")
			(net "P3V3_E1S_EN_0_R")
		)
		(pad "2" smd circle
			(at 0.40005 0 180)
			(size 0 0)
			(layers "F.Cu" "F.Mask" "F.Paste")
			(net "GND")
		)
	)
	(footprint ""
		(layer "F.Cu")
		(at 299.265594 -393.04468)
		(property "Reference" "R980"
			(at 0 0 0)
			(layer "F.SilkS")
			(hide yes)
			(effects
				(font
					(size 1.27 1.27)
				)
			)
		)
		(property "Value" ""
			(at 0 0 0)
			(layer "F.Fab")
			(effects
				(font
					(size 1.27 1.27)
				)
			)
		)
		(duplicate_pad_numbers_are_jumpers no)
		(fp_line
			(start -0.32512 -0.175006)
			(end 0.32512 -0.175006)
			(stroke
				(width 0.1)
				(type default)
			)
			(layer "F.Fab")
		)
		(fp_line
			(start -0.32512 0.175006)
			(end -0.32512 -0.175006)
			(stroke
				(width 0.1)
				(type default)
			)
			(layer "F.Fab")
		)
		(fp_line
			(start 0.32512 -0.175006)
			(end 0.32512 0.175006)
			(stroke
				(width 0.1)
				(type default)
			)
			(layer "F.Fab")
		)
		(fp_line
			(start 0.32512 0.175006)
			(end -0.32512 0.175006)
			(stroke
				(width 0.1)
				(type default)
			)
			(layer "F.Fab")
		)
		(pad "1" smd rect
			(at -0.2667 0)
			(size 0.3048 0.381)
			(layers "F.Cu" "F.Mask" "F.Paste")
			(net "GPIO3_RT_CPU0_P0")
		)
		(pad "2" smd rect
			(at 0.2667 0 180)
			(size 0.3048 0.381)
			(layers "F.Cu" "F.Mask" "F.Paste")
			(net "GND")
		)
	)
)
